FILE_TYPE = CONNECTIVITY;
{Allegro Design Entry HDL 17.4-2019 S026 (4007227) 1/17/2022}
"PAGE_NUMBER" = 201;
0"NC";
1"GND\g";
2"P3V3_AUX\g";
3"GND\g";
4"GND\g";
5"P3V3_AUX\g";
6"GND\g";
7"GND\g";
8"GND\g";
9"GND\g";
10"GND\g";
11"GND\g";
12"P12V_AUX\g";
13"PVDD18_S5_P1\g";
14"GND\g";
15"GND\g";
16"GND\g";
17"PVDD18_S5_P1_FB_RC";
18"SW_PVDD18_S5_P1_SW";
19"SW_PVDD18_S5_P1_BST_R";
20"PVDD18_S5_P1_FB";
21"SW_PVDD18_S5_P1_BST";
22"PVDD18_SS_P1_RGND";
23"PWRGD_PVDD18_S5_P1";
24"SW_P12V_AUX_PVDD18_S5_P1_FLT";
25"PVDD18_S5_P1_EN";
26"VSENSE_PVDD18_S5_P1_DN";
27"VSENSE_PVDD18_S5_P1_DP";
28"PWRGD_PVDD18_S5_R_P1";
29"PVDD18_S5_P1_REF";
30"PVDD18_S5_P1_MODE";
31"PVDD18_S5_P1_VCC";
32"PVDD18_S5_P1_CS";
%"UNIVERSAL_GND"
"1","(-6375,2725)","0","pure_quanta_power","I10";
;
CDS_LIB"pure_quanta_power"
HDL_POWER"GND";
"A"1;
%"Q_RES"
"2","(-6375,2975)","0","pure_quanta","I11";
;
LOCATION"PR8"
SEC"1"
PACK_TYPE"0402LF"
WATTAGE"1/16W"
MATERIAL"CHIP"
TOLERANCE"1%"
VALUE"8.66K"
CDS_LIB"pure_quanta"
SEC_TYPE"0402LF"
PART_NUMBER"CS28662FB02";
"A"
$PN"1"32;
"B"
$PN"2"1;
%"Q_RES"
"2","(-6875,3400)","0","pure_quanta","I12";
;
LOCATION"PR397"
$SEC"1"
CDS_SEC"1"
PACK_TYPE"0402LF"
WATTAGE"1/16W"
MATERIAL"CHIP"
TOLERANCE"5%"
VALUE"0"
CDS_LIB"pure_quanta"
PART_NUMBER"CS00002JB13";
"A"
$PN"1"2;
"B"
$PN"2"31;
%"UNIVERSAL_POWER"
"1","(-6875,3600)","0","mstr_symbols","I13";
;
HDL_POWER"P3V3_AUX"
CDS_LIB"mstr_symbols";
"A"2;
%"Q_RES"
"1","(-6850,3800)","0","pure_quanta","I14";
;
LOCATION"PR398"
$SEC"1"
CDS_SEC"1"
MATERIAL"CHIP"
WATTAGE"1/16W"
PACK_TYPE"0402LF"
TOLERANCE"5%"
VALUE"0"
CDS_LIB"pure_quanta"
PART_NUMBER"CS00002JB13";
"B"
$PN"2"30;
"A"
$PN"1"10;
%"MPQ8633BGLEC838Z"
"1","(-5425,3825)","0","pure_quanta","I15";
;
LOCATION"PU3"
$SEC"1"
CDS_SEC"1"
MATERIAL"IC"
PART_TYPE"SMLF"
VALUE"MPQ8633BGLE-C838-Z"
CDS_LMAN_SYM_OUTLINE"-250,725,250,-725"
NEEDS_NO_SIZE"TRUE"
CDS_LIB"pure_quanta"
PART_NUMBER"AL008633005";
"VIN2"
$PN"21"24;
"CS"
$PN"3"32;
"MODE"
$PN"4"30;
"TRK_REF"
$PN"5"29;
"SW"
$PN"20"18;
"RGND"
$PN"6"22;
"VCC"
$PN"19"31;
"AGND"
$PN"2"16;
"FB"
$PN"7"20;
"BST"
$PN"1"21;
"EN"
$PN"8"25;
"PGND"
$PN"11_18"16;
"PGOOD"
$PN"9"23;
"VIN1"
$PN"10"24;
%"UNIVERSAL_GND"
"1","(-4875,2875)","0","pure_quanta_power","I16";
;
CDS_LIB"pure_quanta_power"
HDL_POWER"GND";
"A"16;
%"UNIVERSAL_GND"
"1","(-4700,2875)","0","pure_quanta_power","I17";
;
CDS_LIB"pure_quanta_power"
HDL_POWER"GND";
"A"3;
%"Q_CAP"
"1","(-4700,3125)","0","pure_quanta","I18";
;
LOCATION"PC153"
$SEC"1"
CDS_SEC"1"
VALUE"0.022UF"
TOLERANCE"10%"
MATERIAL"X7R"
VOLTAGE"25V"
PACK_TYPE"0402"
CDS_LIB"pure_quanta"
PART_NUMBER"CH3224K1B01";
"B"
$PN"2"3;
"A"
$PN"1"29;
%"Q_CAP"
"1","(-4275,3300)","1","pure_quanta","I19";
;
LOCATION"PC62"
$SEC"1"
CDS_SEC"1"
PACK_TYPE"0402"
MATERIAL"X7R"
TOLERANCE"10%"
VALUE"0.1UF"
VOLTAGE"25V"
CDS_LIB"pure_quanta"
PART_NUMBER"CH4104K1B00";
"B"
$PN"2"22;
"A"
$PN"1"29;
%"UNIVERSAL_GND"
"1","(-8800,4225)","0","pure_quanta_power","I2";
;
CDS_LIB"pure_quanta_power"
HDL_POWER"GND";
"A"4;
%"UNIVERSAL_GND"
"1","(-7750,4175)","0","pure_quanta_power","I20";
;
CDS_LIB"pure_quanta_power"
HDL_POWER"GND";
"A"15;
%"Q_CAP"
"1","(-7150,4550)","0","pure_quanta","I21";
;
LOCATION"PC61"
$SEC"1"
CDS_SEC"1"
VOLTAGE"16V"
VALUE"22UF"
MATERIAL"X6S"
PACK_TYPE"C0805"
TOLERANCE"20%"
CDS_LIB"pure_quanta"
PART_NUMBER"CH6223MEA01";
"B"
$PN"2"15;
"A"
$PN"1"24;
%"Q_CAP"
"1","(-6825,4550)","0","pure_quanta","I22";
;
LOCATION"PC150"
$SEC"1"
CDS_SEC"1"
PACK_TYPE"C0805"
MATERIAL"X6S"
VALUE"22UF"
VOLTAGE"16V"
TOLERANCE"20%"
CDS_LIB"pure_quanta"
PART_NUMBER"CH6223MEA01";
"B"
$PN"2"15;
"A"
$PN"1"24;
%"Q_CAP"
"1","(-6575,4550)","0","pure_quanta","I23";
;
LOCATION"PC152"
$SEC"1"
CDS_SEC"1"
TOLERANCE"20%"
VOLTAGE"16V"
VALUE"22UF"
MATERIAL"X6S"
PACK_TYPE"C0805"
CDS_LIB"pure_quanta"
PART_NUMBER"CH6223MEA01";
"B"
$PN"2"15;
"A"
$PN"1"24;
%"Q_CAP"
"1","(-6325,4550)","0","pure_quanta","I24";
;
LOCATION"PC22"
$SEC"1"
CDS_SEC"1"
VOLTAGE"25V"
TOLERANCE"10%"
MATERIAL"X6S"
VALUE"1UF"
PACK_TYPE"C0402"
CDS_LIB"pure_quanta"
PART_NUMBER"CH5104KEB02";
"B"
$PN"2"15;
"A"
$PN"1"24;
%"Q_CAP"
"1","(-3775,4125)","0","pure_quanta","I25";
;
LOCATION"PC19"
SEC"1"
TOLERANCE"10%"
VALUE"0.22UF"
PACK_TYPE"0402"
MATERIAL"X7R"
VOLTAGE"16V"
CDS_LIB"pure_quanta"
SEC_TYPE"0402"
PART_NUMBER"CH4223K1B00";
"B"
$PN"2"18;
"A"
$PN"1"19;
%"Q_RES"
"2","(-4375,4800)","0","pure_quanta","I26";
;
LOCATION"R8009"
SEC"1"
PACK_TYPE"0402LF"
WATTAGE"1/16W"
MATERIAL"CHIP"
VALUE"10K"
TOLERANCE"5%"
CDS_LIB"pure_quanta"
SEC_TYPE"0402LF"
PART_NUMBER"CS31002JB08";
"A"
$PN"1"5;
"B"
$PN"2"23;
%"UNIVERSAL_POWER"
"1","(-4375,5075)","0","mstr_symbols","I27";
;
HDL_POWER"P3V3_AUX"
CDS_LIB"mstr_symbols";
"A"5;
%"UNIVERSAL_GND"
"1","(-3300,2125)","0","pure_quanta_power","I28";
;
CDS_LIB"pure_quanta_power"
HDL_POWER"GND";
"A"6;
%"Q_RES"
"1","(-3300,2350)","1","pure_quanta","I29";
;
LOCATION"PR399"
$SEC"1"
CDS_SEC"1"
TOLERANCE"1%"
MATERIAL"CHIP"
VALUE"49.9"
WATTAGE"1/16W"
PACK_TYPE"0402LF"
CDS_LIB"pure_quanta"
PART_NUMBER"CS04992FB07";
"B"
$PN"2"22;
"A"
$PN"1"6;
%"Q_CAP"
"1","(-8800,4575)","0","pure_quanta","I3";
;
LOCATION"PC6002"
$SEC"1"
CDS_SEC"1"
TOLERANCE"10%"
VOLTAGE"25V"
VALUE"0.1UF"
PACK_TYPE"0402"
MATERIAL"X7R"
SIGNAL_MODEL"DEFAULT_CAPACITOR_100000PF_2_1"
CDS_LIB"pure_quanta"
PART_NUMBER"CH4104K1B00";
"B"
$PN"2"4;
"A"
$PN"1"12;
%"Q_RES"
"2","(-3875,3250)","0","pure_quanta","I30";
;
LOCATION"PR147"
$SEC"1"
CDS_SEC"1"
MATERIAL"CHIP"
TOLERANCE"1%"
PACK_TYPE"0402LF"
WATTAGE"1/16W"
VALUE"10K"
CDS_LIB"pure_quanta"
PART_NUMBER"CS31002FB08";
"A"
$PN"1"20;
"B"
$PN"2"22;
%"Q_CAP"
"2","(-3275,3275)","0","pure_quanta","I31";
;
LOCATION"PC64"
$SEC"1"
CDS_SEC"1"
VALUE"220PF"
TOLERANCE"10%"
PACK_TYPE"0402"
MATERIAL"X7R"
VOLTAGE"50V"
CDS_LIB"pure_quanta"
PART_NUMBER"TMP_QCH12206KB14";
"A"
$PN"1"20;
"B"
$PN"2"17;
%"Q_RES"
"1","(-3275,3550)","0","pure_quanta","I32";
;
LOCATION"PR148"
$SEC"1"
CDS_SEC"1"
VALUE"20K"
MATERIAL"CHIP"
PACK_TYPE"0402LF"
CDS_LIB"pure_quanta"
WATTAGE"1/16W"
TOLERANCE"1%"
PART_NUMBER"CS32002FB06";
"B"
$PN"2"17;
"A"
$PN"1"20;
%"Q_INDUCTOR"
"1","(-3275,4025)","0","pure_quanta","I33";
;
LOCATION"PL57"
$SEC"1"
CDS_SEC"1"
VALUE"1.0UH/18A"
PACK_TYPE"SMLF"
MATERIAL"IND"
CDS_LIB"pure_quanta"
NEEDS_NO_SIZE"TRUE"
PART_NUMBER"CV-10I0MZ01";
"1"
$PN"1"18;
"2"
$PN"2"13;
%"Q_CAP"
"1","(-2750,2625)","0","pure_quanta","I34";
;
LOCATION"PC6006"
$SEC"1"
CDS_SEC"1"
VOLTAGE"25V"
TOLERANCE"10%"
PACK_TYPE"C0402"
VALUE"0.01UF"
MATERIAL"EMPTY"
CDS_LIB"pure_quanta"
PART_NUMBER"CH3104K1B11";
"B"
$PN"2"22;
"A"
$PN"1"17;
%"Q_RES"
"2","(-2150,2500)","1","pure_quanta","I35";
;
LOCATION"PR401"
$SEC"1"
CDS_SEC"1"
TOLERANCE"5%"
MATERIAL"CHIP"
PACK_TYPE"0402LF"
VALUE"0"
WATTAGE"1/16W"
CDS_LIB"pure_quanta"
PART_NUMBER"CS00002JB13";
"A"
$PN"1"22;
"B"
$PN"2"26;
%"Q_RES"
"1","(-2150,2750)","0","pure_quanta","I36";
;
LOCATION"PR400"
$SEC"1"
CDS_SEC"1"
WATTAGE"1/16W"
MATERIAL"CHIP"
PACK_TYPE"0402LF"
VALUE"10"
TOLERANCE"1%"
CDS_LIB"pure_quanta"
PART_NUMBER"CS01002FB07";
"B"
$PN"2"27;
"A"
$PN"1"17;
%"Q_CAP"
"1","(-2450,3750)","0","pure_quanta","I37";
;
LOCATION"PC65"
$SEC"1"
CDS_SEC"1"
MATERIAL"X6S"
TOLERANCE"20%"
VOLTAGE"4V"
PACK_TYPE"C0805"
VALUE"22UF"
CDS_LIB"pure_quanta"
PART_NUMBER"CH622KMEA03";
"B"
$PN"2"14;
"A"
$PN"1"13;
%"Q_CAP"
"1","(-2025,3750)","0","pure_quanta","I38";
;
LOCATION"PC83"
$SEC"1"
CDS_SEC"1"
TOLERANCE"20%"
VALUE"22UF"
VOLTAGE"4V"
PACK_TYPE"C0805"
MATERIAL"X6S"
CDS_LIB"pure_quanta"
PART_NUMBER"CH622KMEA03";
"B"
$PN"2"14;
"A"
$PN"1"13;
%"Q_RES"
"1","(-1450,3225)","2","pure_quanta","I39";
;
LOCATION"PR402"
$SEC"1"
CDS_SEC"1"
PACK_TYPE"0402LF"
WATTAGE"1/16W"
TOLERANCE"1%"
MATERIAL"CHIP"
VALUE"49.9"
CDS_LIB"pure_quanta"
PART_NUMBER"CS04992FB07";
"B"
$PN"2"17;
"A"
$PN"1"13;
%"Q_INDUCTOR"
"1","(-8450,4800)","0","pure_quanta","I4";
;
LOCATION"PL26"
$SEC"1"
CDS_SEC"1"
PACK_TYPE"SMLF"
MATERIAL"IND"
VALUE"BLM18SN220TN1D/8000MA"
NEEDS_NO_SIZE"TRUE"
CDS_LIB"pure_quanta"
PART_NUMBER"CX220TN1001";
"1"
$PN"1"12;
"2"
$PN"2"24;
%"Q_CAP"
"1","(-1825,3750)","0","pure_quanta","I40";
;
LOCATION"PC84"
$SEC"1"
CDS_SEC"1"
VALUE"22UF"
VOLTAGE"4V"
MATERIAL"X6S"
PACK_TYPE"C0805"
TOLERANCE"20%"
CDS_LIB"pure_quanta"
PART_NUMBER"CH622KMEA03";
"B"
$PN"2"14;
"A"
$PN"1"13;
%"Q_CAP"
"1","(-1575,3750)","0","pure_quanta","I41";
;
LOCATION"PC87"
$SEC"1"
CDS_SEC"1"
VOLTAGE"4V"
TOLERANCE"20%"
MATERIAL"EMPTY"
PACK_TYPE"C0805"
VALUE"22UF"
CDS_LIB"pure_quanta"
PART_NUMBER"CH622KMEA03";
"B"
$PN"2"14;
"A"
$PN"1"13;
%"Q_CAP"
"1","(-1250,3750)","0","pure_quanta","I42";
;
LOCATION"PC88"
$SEC"1"
CDS_SEC"1"
PACK_TYPE"C0805"
VOLTAGE"4V"
MATERIAL"EMPTY"
TOLERANCE"20%"
VALUE"22UF"
CDS_LIB"pure_quanta"
PART_NUMBER"CH622KMEA03";
"B"
$PN"2"14;
"A"
$PN"1"13;
%"Q_CAPP"
"1","(-975,3725)","0","pure_quanta","I43";
;
LOCATION"PC89"
$SEC"1"
CDS_SEC"1"
VALUE"390UF"
TOLERANCE"20%"
VOLTAGE"2.5V"
PACK_TYPE"SMLF"
MATERIAL"ALUM"
CDS_LIB"pure_quanta"
PART_NUMBER"CC7390JMZ13";
"A"
$PN"1"13;
"B"
$PN"2"14;
%"UNIVERSAL_GND"
"1","(-600,3375)","0","pure_quanta_power","I46";
;
CDS_LIB"pure_quanta_power"
HDL_POWER"GND";
"A"14;
%"Q_CAP"
"1","(-600,3725)","0","pure_quanta","I47";
;
LOCATION"PC21"
$SEC"1"
CDS_SEC"1"
TOLERANCE"10%"
MATERIAL"X7R"
PACK_TYPE"0402"
VALUE"0.1UF"
VOLTAGE"25V"
CDS_LIB"pure_quanta"
PART_NUMBER"CH4104K1B00";
"B"
$PN"2"14;
"A"
$PN"1"13;
%"Q_RES"
"1","(-3575,4500)","0","pure_quanta","I48";
;
LOCATION"R259"
$SEC"1"
CDS_SEC"1"
VALUE"33"
BOM_COST"MEM"
CDS_LIB"pure_quanta"
WATTAGE"1/16W"
MATERIAL"CHIP"
TOLERANCE"5%"
PACK_TYPE"0402LF"
PART_NUMBER"CS03302JB10";
"B"
$PN"2"28;
"A"
$PN"1"23;
%"P1V0_AUX"
"1","(-8750,5225)","0","mstr_symbols","I5";
;
HDL_POWER"P12V_AUX"
ROOM"VR_DDR1_POWER_STAGE"
VOLTAGE"1.0V"
CDS_LIB"mstr_symbols"
BODY_TYPE"PLUMBING";
"A"12;
%"Q_RES"
"2","(50,3750)","0","pure_quanta","I50";
;
LOCATION"PR403"
$SEC"1"
CDS_SEC"1"
WATTAGE"1/16W"
MATERIAL"CHIP"
TOLERANCE"1%"
VALUE"1K"
PACK_TYPE"0402LF"
CDS_LIB"pure_quanta"
PART_NUMBER"CS21002FB06";
"A"
$PN"1"13;
"B"
$PN"2"7;
%"UNIVERSAL_GND"
"1","(50,3450)","0","pure_quanta_power","I51";
;
CDS_LIB"pure_quanta_power"
HDL_POWER"GND";
"A"7;
%"P1V0"
"1","(50,4525)","0","pure_quanta_power","I52";
;
HDL_POWER"PVDD18_S5_P1"
CDS_LIB"pure_quanta_power";
"A"13;
%"Q_CAP"
"1","(-6875,3035)","2","pure_quanta","I53";
;
LOCATION"PC20"
SEC"1"
PACK_TYPE"C0402"
VOLTAGE"25V"
VALUE"1UF"
TOLERANCE"10%"
MATERIAL"X6S"
SEC_TYPE"C0402"
SIGNAL_MODEL"DEFAULT_CAPACITOR_100000PF_2_1"
CDS_LIB"pure_quanta"
PART_NUMBER"CH5104KEB02";
"B"
$PN"2"11;
"A"
$PN"1"31;
%"Q_CAP"
"1","(-7525,4575)","0","pure_quanta","I54";
;
LOCATION"PC60"
$SEC"1"
CDS_SEC"1"
TOLERANCE"20%"
PACK_TYPE"C0805"
VOLTAGE"16V"
MATERIAL"X6S"
VALUE"22UF"
CDS_LIB"pure_quanta"
PART_NUMBER"CH6223MEA01";
"B"
$PN"2"15;
"A"
$PN"1"24;
%"Q_CAP"
"1","(-2375,4350)","0","pure_quanta","I55";
;
LOCATION"C5016"
$SEC"1"
CDS_SEC"1"
MATERIAL"X7R"
TOLERANCE"5%"
PACK_TYPE"0402"
VALUE"1000PF"
VOLTAGE"50V"
CDS_LIB"pure_quanta"
PART_NUMBER"TMP_QCH21006JB10";
"B"
$PN"2"8;
"A"
$PN"1"28;
%"UNIVERSAL_GND"
"1","(-2375,4150)","0","pure_quanta_power","I56";
;
CDS_LIB"pure_quanta_power"
HDL_POWER"GND";
"A"8;
%"Q_CAP"
"1","(-7850,4575)","0","pure_quanta","I57";
;
LOCATION"PC8003"
$SEC"1"
CDS_SEC"1"
VALUE"22UF"
MATERIAL"X6S"
TOLERANCE"20%"
PACK_TYPE"C0805"
VOLTAGE"16V"
CDS_LIB"pure_quanta"
PART_NUMBER"CH6223MEA01";
"B"
$PN"2"15;
"A"
$PN"1"24;
%"Q_RES"
"1","(-4250,4300)","0","pure_quanta","I58";
;
LOCATION"PR8002"
SEC"1"
TOLERANCE"1%"
VALUE"2.2"
PACK_TYPE"0402LF"
MATERIAL"CHIP"
CDS_LIB"pure_quanta"
WATTAGE"1/16W"
SEC_TYPE"0402LF"
PART_NUMBER"CS-2202FB01";
"B"
$PN"2"19;
"A"
$PN"1"21;
%"Q_CAP"
"1","(-7725,3850)","2","pure_quanta","I6";
;
LOCATION"C675"
$SEC"1"
CDS_SEC"1"
PACK_TYPE"0402"
VOLTAGE"25V"
MATERIAL"EMPTY"
VALUE"0.1UF"
TOLERANCE"10%"
CDS_LIB"pure_quanta"
PART_NUMBER"CH4104K1B00";
"B"
$PN"2"9;
"A"
$PN"1"25;
%"UNIVERSAL_GND"
"1","(-7725,3650)","0","pure_quanta_power","I7";
;
CDS_LIB"pure_quanta_power"
HDL_POWER"GND";
"A"9;
%"UNIVERSAL_GND"
"1","(-7450,3450)","0","pure_quanta_power","I8";
;
CDS_LIB"pure_quanta_power"
HDL_POWER"GND";
"A"10;
%"UNIVERSAL_GND"
"1","(-6875,2750)","0","pure_quanta_power","I9";
;
CDS_LIB"pure_quanta_power"
HDL_POWER"GND";
"A"11;
END.
